(kicad_pcb
	(version 20260206)
	(generator "pcbnew")
	(generator_version "10.0")
	(general
		(thickness 1.6)
		(legacy_teardrops no)
	)
	(paper "A4")
	(title_block
		(title "01162023_DA0F0TEBIF0_F0T_Expander_BD_F_brd_V02_OCP.brd")
		(comment 1 "Grand Teton / footprints 3141-3146 of 9728")
	)
	(layers
		(0 "F.Cu" signal "TOP")
		(4 "In1.Cu" signal "GND")
		(6 "In2.Cu" signal "VCC")
		(8 "In3.Cu" signal "VCC1")
		(10 "In4.Cu" signal "GND1")
		(12 "In5.Cu" signal "IN1")
		(14 "In6.Cu" signal "GND2")
		(16 "In7.Cu" signal "IN2")
		(18 "In8.Cu" signal "GND3")
		(20 "In9.Cu" signal "IN3")
		(22 "In10.Cu" signal "GND4")
		(24 "In11.Cu" signal "IN4")
		(26 "In12.Cu" signal "GND5")
		(28 "In13.Cu" signal "IN5")
		(30 "In14.Cu" signal "GND6")
		(32 "In15.Cu" signal "IN6")
		(34 "In16.Cu" signal "GND7")
		(2 "B.Cu" signal "BOTTOM")
		(9 "F.Adhes" user "F.Adhesive")
		(11 "B.Adhes" user "B.Adhesive")
		(13 "F.Paste" user "Package Geometry/Pastemask Top")
		(15 "B.Paste" user "Package Geometry/Pastemask Bottom")
		(5 "F.SilkS" user "Ref Des/Silkscreen Top")
		(7 "B.SilkS" user "Ref Des/Silkscreen Bottom")
		(1 "F.Mask" user "Board Geometry/Soldermask Top")
		(3 "B.Mask" user "Board Geometry/Soldermask Bottom")
		(17 "Dwgs.User" user "User.Drawings")
		(19 "Cmts.User" user "User.Comments")
		(21 "Eco1.User" user "User.Eco1")
		(23 "Eco2.User" user "User.Eco2")
		(25 "Edge.Cuts" user "Board Geometry/Outline")
		(27 "Margin" user)
		(31 "F.CrtYd" user "Package Geometry/Place Bound Top")
		(29 "B.CrtYd" user "Package Geometry/Place Bound Bottom")
		(35 "F.Fab" user "Ref Des/Assembly Top")
		(33 "B.Fab" user "Ref Des/Assembly Bottom")
	)
	(footprint ""
		(layer "F.Cu")
		(at 327.53173 -226.000818)
		(property "Reference" "R6178"
			(at 0 0 0)
			(layer "F.SilkS")
			(hide yes)
			(effects
				(font
					(size 1.27 1.27)
				)
			)
		)
		(property "Value" ""
			(at 0 0 0)
			(layer "F.Fab")
			(effects
				(font
					(size 1.27 1.27)
				)
			)
		)
		(duplicate_pad_numbers_are_jumpers no)
		(fp_line
			(start -0.7874 -0.4064)
			(end 0.7874 -0.4064)
			(stroke
				(width 0.1524)
				(type default)
			)
			(layer "F.SilkS")
		)
		(fp_line
			(start -0.7874 0.4064)
			(end -0.7874 -0.4064)
			(stroke
				(width 0.1524)
				(type default)
			)
			(layer "F.SilkS")
		)
		(fp_line
			(start 0.7874 -0.4064)
			(end 0.7874 0.4064)
			(stroke
				(width 0.1524)
				(type default)
			)
			(layer "F.SilkS")
		)
		(fp_line
			(start 0.7874 0.4064)
			(end -0.7874 0.4064)
			(stroke
				(width 0.1524)
				(type default)
			)
			(layer "F.SilkS")
		)
		(fp_line
			(start -0.67945 -0.305054)
			(end -0.12065 -0.305054)
			(stroke
				(width 0.1)
				(type default)
			)
			(layer "F.Fab")
		)
		(fp_line
			(start -0.67945 0.3048)
			(end -0.67945 -0.305054)
			(stroke
				(width 0.1)
				(type default)
			)
			(layer "F.Fab")
		)
		(fp_line
			(start -0.12065 -0.305054)
			(end -0.12065 -0.2794)
			(stroke
				(width 0.1)
				(type default)
			)
			(layer "F.Fab")
		)
		(fp_line
			(start -0.12065 -0.2794)
			(end 0.12065 -0.2794)
			(stroke
				(width 0.1)
				(type default)
			)
			(layer "F.Fab")
		)
		(fp_line
			(start -0.12065 0.2794)
			(end -0.12065 0.3048)
			(stroke
				(width 0.1)
				(type default)
			)
			(layer "F.Fab")
		)
		(fp_line
			(start -0.12065 0.3048)
			(end -0.67945 0.3048)
			(stroke
				(width 0.1)
				(type default)
			)
			(layer "F.Fab")
		)
		(fp_line
			(start 0.120396 0.2794)
			(end -0.12065 0.2794)
			(stroke
				(width 0.1)
				(type default)
			)
			(layer "F.Fab")
		)
		(fp_line
			(start 0.120396 0.3048)
			(end 0.120396 0.2794)
			(stroke
				(width 0.1)
				(type default)
			)
			(layer "F.Fab")
		)
		(fp_line
			(start 0.12065 -0.3048)
			(end 0.67945 -0.3048)
			(stroke
				(width 0.1)
				(type default)
			)
			(layer "F.Fab")
		)
		(fp_line
			(start 0.12065 -0.2794)
			(end 0.12065 -0.3048)
			(stroke
				(width 0.1)
				(type default)
			)
			(layer "F.Fab")
		)
		(fp_line
			(start 0.67945 -0.3048)
			(end 0.67945 0.3048)
			(stroke
				(width 0.1)
				(type default)
			)
			(layer "F.Fab")
		)
		(fp_line
			(start 0.67945 0.3048)
			(end 0.120396 0.3048)
			(stroke
				(width 0.1)
				(type default)
			)
			(layer "F.Fab")
		)
		(pad "1" smd circle
			(at -0.40005 0)
			(size 0 0)
			(layers "F.Cu" "F.Mask" "F.Paste")
			(net "GND")
		)
		(pad "2" smd circle
			(at 0.40005 0)
			(size 0 0)
			(layers "F.Cu" "F.Mask" "F.Paste")
			(net "PWR_EN_PEX")
		)
	)
	(footprint ""
		(layer "F.Cu")
		(at 130.88239 -184.656984 -90)
		(property "Reference" "R1116"
			(at 0 0 270)
			(layer "F.SilkS")
			(hide yes)
			(effects
				(font
					(size 1.27 1.27)
				)
			)
		)
		(property "Value" ""
			(at 0 0 270)
			(layer "F.Fab")
			(effects
				(font
					(size 1.27 1.27)
				)
			)
		)
		(duplicate_pad_numbers_are_jumpers no)
		(fp_line
			(start -0.7874 -0.4064)
			(end 0.7874 -0.4064)
			(stroke
				(width 0.1524)
				(type default)
			)
			(layer "F.SilkS")
		)
		(fp_line
			(start -0.67945 0.3048)
			(end -0.67945 -0.305054)
			(stroke
				(width 0.1)
				(type default)
			)
			(layer "F.Fab")
		)
		(fp_line
			(start -0.12065 0.3048)
			(end -0.67945 0.3048)
			(stroke
				(width 0.1)
				(type default)
			)
			(layer "F.Fab")
		)
		(fp_line
			(start 0.120396 0.3048)
			(end 0.120396 0.2794)
			(stroke
				(width 0.1)
				(type default)
			)
			(layer "F.Fab")
		)
		(fp_line
			(start 0.67945 0.3048)
			(end 0.120396 0.3048)
			(stroke
				(width 0.1)
				(type default)
			)
			(layer "F.Fab")
		)
		(fp_line
			(start -0.12065 0.2794)
			(end -0.12065 0.3048)
			(stroke
				(width 0.1)
				(type default)
			)
			(layer "F.Fab")
		)
		(fp_line
			(start 0.120396 0.2794)
			(end -0.12065 0.2794)
			(stroke
				(width 0.1)
				(type default)
			)
			(layer "F.Fab")
		)
		(fp_line
			(start -0.12065 -0.2794)
			(end 0.12065 -0.2794)
			(stroke
				(width 0.1)
				(type default)
			)
			(layer "F.Fab")
		)
		(fp_line
			(start 0.12065 -0.2794)
			(end 0.12065 -0.3048)
			(stroke
				(width 0.1)
				(type default)
			)
			(layer "F.Fab")
		)
		(fp_line
			(start 0.12065 -0.3048)
			(end 0.67945 -0.3048)
			(stroke
				(width 0.1)
				(type default)
			)
			(layer "F.Fab")
		)
		(fp_line
			(start 0.67945 -0.3048)
			(end 0.67945 0.3048)
			(stroke
				(width 0.1)
				(type default)
			)
			(layer "F.Fab")
		)
		(fp_line
			(start -0.67945 -0.305054)
			(end -0.12065 -0.305054)
			(stroke
				(width 0.1)
				(type default)
			)
			(layer "F.Fab")
		)
		(fp_line
			(start -0.12065 -0.305054)
			(end -0.12065 -0.2794)
			(stroke
				(width 0.1)
				(type default)
			)
			(layer "F.Fab")
		)
		(pad "1" smd circle
			(at -0.40005 0 270)
			(size 0 0)
			(layers "F.Cu" "F.Mask" "F.Paste")
			(net "CLK_100M_DB2000QL_GPU_REF2_R_DP")
		)
		(pad "2" smd circle
			(at 0.40005 0 270)
			(size 0 0)
			(layers "F.Cu" "F.Mask" "F.Paste")
			(net "CLK_100M_DB2000QL_GPU_REF2_DP")
		)
	)
	(footprint ""
		(layer "F.Cu")
		(at 75.65644 -17.419574 180)
		(property "Reference" "R1646"
			(at 0 0 180)
			(layer "F.SilkS")
			(hide yes)
			(effects
				(font
					(size 1.27 1.27)
				)
			)
		)
		(property "Value" ""
			(at 0 0 180)
			(layer "F.Fab")
			(effects
				(font
					(size 1.27 1.27)
				)
			)
		)
		(duplicate_pad_numbers_are_jumpers no)
		(fp_line
			(start 0.7874 0.4064)
			(end -0.7874 0.4064)
			(stroke
				(width 0.1524)
				(type default)
			)
			(layer "F.SilkS")
		)
		(fp_line
			(start 0.7874 -0.4064)
			(end 0.7874 0.4064)
			(stroke
				(width 0.1524)
				(type default)
			)
			(layer "F.SilkS")
		)
		(fp_line
			(start -0.7874 0.4064)
			(end -0.7874 -0.4064)
			(stroke
				(width 0.1524)
				(type default)
			)
			(layer "F.SilkS")
		)
		(fp_line
			(start -0.7874 -0.4064)
			(end 0.7874 -0.4064)
			(stroke
				(width 0.1524)
				(type default)
			)
			(layer "F.SilkS")
		)
		(fp_line
			(start 0.67945 0.3048)
			(end 0.120396 0.3048)
			(stroke
				(width 0.1)
				(type default)
			)
			(layer "F.Fab")
		)
		(fp_line
			(start 0.67945 -0.3048)
			(end 0.67945 0.3048)
			(stroke
				(width 0.1)
				(type default)
			)
			(layer "F.Fab")
		)
		(fp_line
			(start 0.12065 -0.2794)
			(end 0.12065 -0.3048)
			(stroke
				(width 0.1)
				(type default)
			)
			(layer "F.Fab")
		)
		(fp_line
			(start 0.12065 -0.3048)
			(end 0.67945 -0.3048)
			(stroke
				(width 0.1)
				(type default)
			)
			(layer "F.Fab")
		)
		(fp_line
			(start 0.120396 0.3048)
			(end 0.120396 0.2794)
			(stroke
				(width 0.1)
				(type default)
			)
			(layer "F.Fab")
		)
		(fp_line
			(start 0.120396 0.2794)
			(end -0.12065 0.2794)
			(stroke
				(width 0.1)
				(type default)
			)
			(layer "F.Fab")
		)
		(fp_line
			(start -0.12065 0.3048)
			(end -0.67945 0.3048)
			(stroke
				(width 0.1)
				(type default)
			)
			(layer "F.Fab")
		)
		(fp_line
			(start -0.12065 0.2794)
			(end -0.12065 0.3048)
			(stroke
				(width 0.1)
				(type default)
			)
			(layer "F.Fab")
		)
		(fp_line
			(start -0.12065 -0.2794)
			(end 0.12065 -0.2794)
			(stroke
				(width 0.1)
				(type default)
			)
			(layer "F.Fab")
		)
		(fp_line
			(start -0.12065 -0.305054)
			(end -0.12065 -0.2794)
			(stroke
				(width 0.1)
				(type default)
			)
			(layer "F.Fab")
		)
		(fp_line
			(start -0.67945 0.3048)
			(end -0.67945 -0.305054)
			(stroke
				(width 0.1)
				(type default)
			)
			(layer "F.Fab")
		)
		(fp_line
			(start -0.67945 -0.305054)
			(end -0.12065 -0.305054)
			(stroke
				(width 0.1)
				(type default)
			)
			(layer "F.Fab")
		)
		(pad "1" smd circle
			(at -0.40005 0 180)
			(size 0 0)
			(layers "F.Cu" "F.Mask" "F.Paste")
			(net "P3V3_SSD2")
		)
		(pad "2" smd circle
			(at 0.40005 0 180)
			(size 0 0)
			(layers "F.Cu" "F.Mask" "F.Paste")
			(net "SMB_ISO_SSD2_SCL")
		)
	)
	(footprint ""
		(layer "F.Cu")
		(at 262.08355 -61.487812 180)
		(property "Reference" "R5995"
			(at 0 0 180)
			(layer "F.SilkS")
			(hide yes)
			(effects
				(font
					(size 1.27 1.27)
				)
			)
		)
		(property "Value" ""
			(at 0 0 180)
			(layer "F.Fab")
			(effects
				(font
					(size 1.27 1.27)
				)
			)
		)
		(duplicate_pad_numbers_are_jumpers no)
		(fp_line
			(start 0.7874 0.4064)
			(end -0.7874 0.4064)
			(stroke
				(width 0.1524)
				(type default)
			)
			(layer "F.SilkS")
		)
		(fp_line
			(start 0.7874 -0.4064)
			(end 0.7874 0.4064)
			(stroke
				(width 0.1524)
				(type default)
			)
			(layer "F.SilkS")
		)
		(fp_line
			(start -0.7874 0.4064)
			(end -0.7874 -0.4064)
			(stroke
				(width 0.1524)
				(type default)
			)
			(layer "F.SilkS")
		)
		(fp_line
			(start -0.7874 -0.4064)
			(end 0.7874 -0.4064)
			(stroke
				(width 0.1524)
				(type default)
			)
			(layer "F.SilkS")
		)
		(fp_line
			(start 0.67945 0.3048)
			(end 0.120396 0.3048)
			(stroke
				(width 0.1)
				(type default)
			)
			(layer "F.Fab")
		)
		(fp_line
			(start 0.67945 -0.3048)
			(end 0.67945 0.3048)
			(stroke
				(width 0.1)
				(type default)
			)
			(layer "F.Fab")
		)
		(fp_line
			(start 0.12065 -0.2794)
			(end 0.12065 -0.3048)
			(stroke
				(width 0.1)
				(type default)
			)
			(layer "F.Fab")
		)
		(fp_line
			(start 0.12065 -0.3048)
			(end 0.67945 -0.3048)
			(stroke
				(width 0.1)
				(type default)
			)
			(layer "F.Fab")
		)
		(fp_line
			(start 0.120396 0.3048)
			(end 0.120396 0.2794)
			(stroke
				(width 0.1)
				(type default)
			)
			(layer "F.Fab")
		)
		(fp_line
			(start 0.120396 0.2794)
			(end -0.12065 0.2794)
			(stroke
				(width 0.1)
				(type default)
			)
			(layer "F.Fab")
		)
		(fp_line
			(start -0.12065 0.3048)
			(end -0.67945 0.3048)
			(stroke
				(width 0.1)
				(type default)
			)
			(layer "F.Fab")
		)
		(fp_line
			(start -0.12065 0.2794)
			(end -0.12065 0.3048)
			(stroke
				(width 0.1)
				(type default)
			)
			(layer "F.Fab")
		)
		(fp_line
			(start -0.12065 -0.2794)
			(end 0.12065 -0.2794)
			(stroke
				(width 0.1)
				(type default)
			)
			(layer "F.Fab")
		)
		(fp_line
			(start -0.12065 -0.305054)
			(end -0.12065 -0.2794)
			(stroke
				(width 0.1)
				(type default)
			)
			(layer "F.Fab")
		)
		(fp_line
			(start -0.67945 0.3048)
			(end -0.67945 -0.305054)
			(stroke
				(width 0.1)
				(type default)
			)
			(layer "F.Fab")
		)
		(fp_line
			(start -0.67945 -0.305054)
			(end -0.12065 -0.305054)
			(stroke
				(width 0.1)
				(type default)
			)
			(layer "F.Fab")
		)
		(pad "1" smd circle
			(at -0.40005 0 180)
			(size 0 0)
			(layers "F.Cu" "F.Mask" "F.Paste")
			(net "PWRGD_P12V_SSD9_D")
		)
		(pad "2" smd circle
			(at 0.40005 0 180)
			(size 0 0)
			(layers "F.Cu" "F.Mask" "F.Paste")
			(net "PWRGD_P12V_SSD9_R")
		)
	)
	(footprint ""
		(layer "F.Cu")
		(at 226.804474 -136.669272 -90)
		(property "Reference" "R4190"
			(at 0 0 270)
			(layer "F.SilkS")
			(hide yes)
			(effects
				(font
					(size 1.27 1.27)
				)
			)
		)
		(property "Value" ""
			(at 0 0 270)
			(layer "F.Fab")
			(effects
				(font
					(size 1.27 1.27)
				)
			)
		)
		(duplicate_pad_numbers_are_jumpers no)
		(fp_line
			(start -0.7874 0.4064)
			(end -0.7874 -0.4064)
			(stroke
				(width 0.1524)
				(type default)
			)
			(layer "F.SilkS")
		)
		(fp_line
			(start 0.7874 0.4064)
			(end -0.7874 0.4064)
			(stroke
				(width 0.1524)
				(type default)
			)
			(layer "F.SilkS")
		)
		(fp_line
			(start -0.7874 -0.4064)
			(end 0.7874 -0.4064)
			(stroke
				(width 0.1524)
				(type default)
			)
			(layer "F.SilkS")
		)
		(fp_line
			(start 0.7874 -0.4064)
			(end 0.7874 0.4064)
			(stroke
				(width 0.1524)
				(type default)
			)
			(layer "F.SilkS")
		)
		(fp_line
			(start -0.67945 0.3048)
			(end -0.67945 -0.305054)
			(stroke
				(width 0.1)
				(type default)
			)
			(layer "F.Fab")
		)
		(fp_line
			(start -0.12065 0.3048)
			(end -0.67945 0.3048)
			(stroke
				(width 0.1)
				(type default)
			)
			(layer "F.Fab")
		)
		(fp_line
			(start 0.120396 0.3048)
			(end 0.120396 0.2794)
			(stroke
				(width 0.1)
				(type default)
			)
			(layer "F.Fab")
		)
		(fp_line
			(start 0.67945 0.3048)
			(end 0.120396 0.3048)
			(stroke
				(width 0.1)
				(type default)
			)
			(layer "F.Fab")
		)
		(fp_line
			(start -0.12065 0.2794)
			(end -0.12065 0.3048)
			(stroke
				(width 0.1)
				(type default)
			)
			(layer "F.Fab")
		)
		(fp_line
			(start 0.120396 0.2794)
			(end -0.12065 0.2794)
			(stroke
				(width 0.1)
				(type default)
			)
			(layer "F.Fab")
		)
		(fp_line
			(start -0.12065 -0.2794)
			(end 0.12065 -0.2794)
			(stroke
				(width 0.1)
				(type default)
			)
			(layer "F.Fab")
		)
		(fp_line
			(start 0.12065 -0.2794)
			(end 0.12065 -0.3048)
			(stroke
				(width 0.1)
				(type default)
			)
			(layer "F.Fab")
		)
		(fp_line
			(start 0.12065 -0.3048)
			(end 0.67945 -0.3048)
			(stroke
				(width 0.1)
				(type default)
			)
			(layer "F.Fab")
		)
		(fp_line
			(start 0.67945 -0.3048)
			(end 0.67945 0.3048)
			(stroke
				(width 0.1)
				(type default)
			)
			(layer "F.Fab")
		)
		(fp_line
			(start -0.67945 -0.305054)
			(end -0.12065 -0.305054)
			(stroke
				(width 0.1)
				(type default)
			)
			(layer "F.Fab")
		)
		(fp_line
			(start -0.12065 -0.305054)
			(end -0.12065 -0.2794)
			(stroke
				(width 0.1)
				(type default)
			)
			(layer "F.Fab")
		)
		(pad "1" smd circle
			(at -0.40005 0 270)
			(size 0 0)
			(layers "F.Cu" "F.Mask" "F.Paste")
			(net "CLK_CK440_PEX_SMB_ADDR1")
		)
		(pad "2" smd circle
			(at 0.40005 0 270)
			(size 0 0)
			(layers "F.Cu" "F.Mask" "F.Paste")
			(net "P3V3")
		)
	)
	(footprint ""
		(layer "F.Cu")
		(at 206.623158 -82.643472)
		(property "Reference" "R4304"
			(at 0 0 0)
			(layer "F.SilkS")
			(hide yes)
			(effects
				(font
					(size 1.27 1.27)
				)
			)
		)
		(property "Value" ""
			(at 0 0 0)
			(layer "F.Fab")
			(effects
				(font
					(size 1.27 1.27)
				)
			)
		)
		(duplicate_pad_numbers_are_jumpers no)
		(fp_line
			(start -0.7874 -0.4064)
			(end 0.7874 -0.4064)
			(stroke
				(width 0.1524)
				(type default)
			)
			(layer "F.SilkS")
		)
		(fp_line
			(start -0.7874 0.4064)
			(end -0.7874 -0.4064)
			(stroke
				(width 0.1524)
				(type default)
			)
			(layer "F.SilkS")
		)
		(fp_line
			(start 0.7874 -0.4064)
			(end 0.7874 0.4064)
			(stroke
				(width 0.1524)
				(type default)
			)
			(layer "F.SilkS")
		)
		(fp_line
			(start 0.7874 0.4064)
			(end -0.7874 0.4064)
			(stroke
				(width 0.1524)
				(type default)
			)
			(layer "F.SilkS")
		)
		(fp_line
			(start -0.67945 -0.305054)
			(end -0.12065 -0.305054)
			(stroke
				(width 0.1)
				(type default)
			)
			(layer "F.Fab")
		)
		(fp_line
			(start -0.67945 0.3048)
			(end -0.67945 -0.305054)
			(stroke
				(width 0.1)
				(type default)
			)
			(layer "F.Fab")
		)
		(fp_line
			(start -0.12065 -0.305054)
			(end -0.12065 -0.2794)
			(stroke
				(width 0.1)
				(type default)
			)
			(layer "F.Fab")
		)
		(fp_line
			(start -0.12065 -0.2794)
			(end 0.12065 -0.2794)
			(stroke
				(width 0.1)
				(type default)
			)
			(layer "F.Fab")
		)
		(fp_line
			(start -0.12065 0.2794)
			(end -0.12065 0.3048)
			(stroke
				(width 0.1)
				(type default)
			)
			(layer "F.Fab")
		)
		(fp_line
			(start -0.12065 0.3048)
			(end -0.67945 0.3048)
			(stroke
				(width 0.1)
				(type default)
			)
			(layer "F.Fab")
		)
		(fp_line
			(start 0.120396 0.2794)
			(end -0.12065 0.2794)
			(stroke
				(width 0.1)
				(type default)
			)
			(layer "F.Fab")
		)
		(fp_line
			(start 0.120396 0.3048)
			(end 0.120396 0.2794)
			(stroke
				(width 0.1)
				(type default)
			)
			(layer "F.Fab")
		)
		(fp_line
			(start 0.12065 -0.3048)
			(end 0.67945 -0.3048)
			(stroke
				(width 0.1)
				(type default)
			)
			(layer "F.Fab")
		)
		(fp_line
			(start 0.12065 -0.2794)
			(end 0.12065 -0.3048)
			(stroke
				(width 0.1)
				(type default)
			)
			(layer "F.Fab")
		)
		(fp_line
			(start 0.67945 -0.3048)
			(end 0.67945 0.3048)
			(stroke
				(width 0.1)
				(type default)
			)
			(layer "F.Fab")
		)
		(fp_line
			(start 0.67945 0.3048)
			(end 0.120396 0.3048)
			(stroke
				(width 0.1)
				(type default)
			)
			(layer "F.Fab")
		)
		(pad "1" smd circle
			(at -0.40005 0)
			(size 0 0)
			(layers "F.Cu" "F.Mask" "F.Paste")
			(net "SSD2_LED_R")
		)
		(pad "2" smd circle
			(at 0.40005 0)
			(size 0 0)
			(layers "F.Cu" "F.Mask" "F.Paste")
			(net "SSD2_LED")
		)
	)
)
